# BASEBOARD_FAB2 (Tioga Pass) — schematic netlist excerpt (pin names and nets, part order shuffled) for the footprints in the layout excerpt that follows; sources: Cadence DE-HDL packaged netlist, KiCad conversion of Wiwynn_Tioga_Pass_MB.brd

R6P17  RES  42.2 1.0% EMPTY  pkg 0402  page 103 : A = CLK_100M_CPU0_BCLK0_DP ; B = GND
R2T58  RES  0.0 5% EMPTY  pkg 0402  page 93 : A = H_CPU_ERR0_PCH_N ; B = FM_CPU_ERR0_LVT3_K_N
C1R5  CAP  0.22UF 16V 10% X7R  pkg 0402  page 106 : A = P3E_CPU0_PE3_OCP_TXN<2> ; B = P3E_OCP_CPU0_PE3_C_TXN<2>

(kicad_pcb
	(version 20260206)
	(generator "pcbnew")
	(generator_version "10.0")
	(general
		(thickness 1.6)
		(legacy_teardrops no)
	)
	(paper "A4")
	(title_block
		(title "Wiwynn_Tioga_Pass_MB.brd")
		(comment 1 "Tioga Pass / footprints 2709-2711 of 4770")
	)
	(layers
		(0 "F.Cu" signal "TOP")
		(4 "In1.Cu" signal "L2GND")
		(6 "In2.Cu" signal "L3")
		(8 "In3.Cu" signal "L4GND")
		(10 "In4.Cu" signal "L5")
		(12 "In5.Cu" signal "L6GND")
		(14 "In6.Cu" signal "L7VCC")
		(16 "In7.Cu" signal "L8VCC")
		(18 "In8.Cu" signal "L9GND")
		(20 "In9.Cu" signal "L10")
		(22 "In10.Cu" signal "L11GND")
		(24 "In11.Cu" signal "L12")
		(26 "In12.Cu" signal "L13GND")
		(2 "B.Cu" signal "BOTTOM")
		(9 "F.Adhes" user "F.Adhesive")
		(11 "B.Adhes" user "B.Adhesive")
		(13 "F.Paste" user "Package Geometry/Pastemask Top")
		(15 "B.Paste" user "Package Geometry/Pastemask Bottom")
		(5 "F.SilkS" user "Ref Des/Silkscreen Top")
		(7 "B.SilkS" user "Ref Des/Silkscreen Bottom")
		(1 "F.Mask" user "Board Geometry/Soldermask Top")
		(3 "B.Mask" user "Board Geometry/Soldermask Bottom")
		(17 "Dwgs.User" user "User.Drawings")
		(19 "Cmts.User" user "User.Comments")
		(21 "Eco1.User" user "User.Eco1")
		(23 "Eco2.User" user "User.Eco2")
		(25 "Edge.Cuts" user "Board Geometry/Outline")
		(27 "Margin" user)
		(31 "F.CrtYd" user "Package Geometry/Place Bound Top")
		(29 "B.CrtYd" user "Package Geometry/Place Bound Bottom")
		(35 "F.Fab" user "Ref Des/Assembly Top")
		(33 "B.Fab" user "Ref Des/Assembly Bottom")
	)
	(footprint ""
		(layer "B.Cu")
		(at 360.555794 -41.543986 90)
		(property "Reference" "R2T58"
			(at 0 0 90)
			(layer "B.SilkS")
			(hide yes)
			(effects
				(font
					(size 1.27 1.27)
				)
				(justify mirror)
			)
		)
		(property "Value" ""
			(at 0 0 90)
			(layer "B.Fab")
			(effects
				(font
					(size 1.27 1.27)
				)
				(justify mirror)
			)
		)
		(duplicate_pad_numbers_are_jumpers no)
		(fp_poly
			(pts
				(xy 0.2794 -0.1016) (xy -0.2794 -0.1016) (xy -0.2794 0.9906) (xy 0.2794 0.9906)
			)
			(stroke
				(width 0)
				(type default)
			)
			(fill no)
			(layer "B.CrtYd")
		)
		(fp_line
			(start 0.2794 -0.1016)
			(end 0.2794 0.9906)
			(stroke
				(width 0.1)
				(type default)
			)
			(layer "B.Fab")
		)
		(fp_line
			(start -0.2794 -0.1016)
			(end 0.2794 -0.1016)
			(stroke
				(width 0.1)
				(type default)
			)
			(layer "B.Fab")
		)
		(fp_line
			(start 0.2794 0.9906)
			(end -0.2794 0.9906)
			(stroke
				(width 0.1)
				(type default)
			)
			(layer "B.Fab")
		)
		(fp_line
			(start -0.2794 0.9906)
			(end -0.2794 -0.1016)
			(stroke
				(width 0.1)
				(type default)
			)
			(layer "B.Fab")
		)
		(pad "1" smd rect
			(at 0 0 270)
			(size 0.508 0.508)
			(layers "B.Cu" "B.Mask" "B.Paste")
			(net "H_CPU_ERR0_PCH_N")
		)
		(pad "2" smd rect
			(at 0 0.889 270)
			(size 0.508 0.508)
			(layers "B.Cu" "B.Mask" "B.Paste")
			(net "FM_CPU_ERR0_LVT3_K_N")
		)
		(zone
			(layer "B.Cu")
			(hatch none 0.5)
			(connect_pads
				(clearance 0)
			)
			(min_thickness 0.25)
			(keepout
				(tracks allowed)
				(vias not_allowed)
				(pads allowed)
				(copperpour not_allowed)
				(footprints allowed)
			)
			(placement
				(enabled no)
				(sheetname "")
			)
			(fill
				(thermal_gap 0.5)
				(thermal_bridge_width 0.5)
				(island_removal_mode 0)
			)
			(polygon
				(pts
					(xy 360.809794 -41.797986) (xy 360.809794 -41.289986) (xy 361.190794 -41.289986) (xy 361.190794 -41.797986)
				)
			)
		)
		(zone
			(layer "B.Cu")
			(hatch none 0.5)
			(connect_pads
				(clearance 0)
			)
			(min_thickness 0.25)
			(keepout
				(tracks not_allowed)
				(vias allowed)
				(pads allowed)
				(copperpour not_allowed)
				(footprints allowed)
			)
			(placement
				(enabled no)
				(sheetname "")
			)
			(fill
				(thermal_gap 0.5)
				(thermal_bridge_width 0.5)
				(island_removal_mode 0)
			)
			(polygon
				(pts
					(xy 361.190794 -41.797986) (xy 361.190794 -41.289986) (xy 360.809794 -41.289986) (xy 360.809794 -41.797986)
				)
			)
		)
	)
	(footprint ""
		(layer "B.Cu")
		(at 176.149 -76.327 -90)
		(property "Reference" "R6P17"
			(at 0 0 90)
			(layer "B.SilkS")
			(hide yes)
			(effects
				(font
					(size 1.27 1.27)
				)
				(justify mirror)
			)
		)
		(property "Value" ""
			(at 0 0 90)
			(layer "B.Fab")
			(effects
				(font
					(size 1.27 1.27)
				)
				(justify mirror)
			)
		)
		(duplicate_pad_numbers_are_jumpers no)
		(fp_poly
			(pts
				(xy 0.2794 -0.1016) (xy -0.2794 -0.1016) (xy -0.2794 0.9906) (xy 0.2794 0.9906)
			)
			(stroke
				(width 0)
				(type default)
			)
			(fill no)
			(layer "B.CrtYd")
		)
		(fp_line
			(start -0.2794 0.9906)
			(end -0.2794 -0.1016)
			(stroke
				(width 0.1)
				(type default)
			)
			(layer "B.Fab")
		)
		(fp_line
			(start 0.2794 0.9906)
			(end -0.2794 0.9906)
			(stroke
				(width 0.1)
				(type default)
			)
			(layer "B.Fab")
		)
		(fp_line
			(start -0.2794 -0.1016)
			(end 0.2794 -0.1016)
			(stroke
				(width 0.1)
				(type default)
			)
			(layer "B.Fab")
		)
		(fp_line
			(start 0.2794 -0.1016)
			(end 0.2794 0.9906)
			(stroke
				(width 0.1)
				(type default)
			)
			(layer "B.Fab")
		)
		(pad "1" smd rect
			(at 0 0 90)
			(size 0.508 0.508)
			(layers "B.Cu" "B.Mask" "B.Paste")
			(net "CLK_100M_CPU0_BCLK0_DP")
		)
		(pad "2" smd rect
			(at 0 0.889 90)
			(size 0.508 0.508)
			(layers "B.Cu" "B.Mask" "B.Paste")
			(net "GND")
		)
		(zone
			(layer "B.Cu")
			(hatch none 0.5)
			(connect_pads
				(clearance 0)
			)
			(min_thickness 0.25)
			(keepout
				(tracks not_allowed)
				(vias allowed)
				(pads allowed)
				(copperpour not_allowed)
				(footprints allowed)
			)
			(placement
				(enabled no)
				(sheetname "")
			)
			(fill
				(thermal_gap 0.5)
				(thermal_bridge_width 0.5)
				(island_removal_mode 0)
			)
			(polygon
				(pts
					(xy 175.514 -76.073) (xy 175.514 -76.581) (xy 175.895 -76.581) (xy 175.895 -76.073)
				)
			)
		)
		(zone
			(layer "B.Cu")
			(hatch none 0.5)
			(connect_pads
				(clearance 0)
			)
			(min_thickness 0.25)
			(keepout
				(tracks allowed)
				(vias not_allowed)
				(pads allowed)
				(copperpour not_allowed)
				(footprints allowed)
			)
			(placement
				(enabled no)
				(sheetname "")
			)
			(fill
				(thermal_gap 0.5)
				(thermal_bridge_width 0.5)
				(island_removal_mode 0)
			)
			(polygon
				(pts
					(xy 175.895 -76.073) (xy 175.895 -76.581) (xy 175.514 -76.581) (xy 175.514 -76.073)
				)
			)
		)
	)
	(footprint ""
		(layer "B.Cu")
		(at 457.5048 -52.483258)
		(property "Reference" "C1R5"
			(at 0 0 0)
			(layer "B.SilkS")
			(hide yes)
			(effects
				(font
					(size 1.27 1.27)
				)
				(justify mirror)
			)
		)
		(property "Value" ""
			(at 0 0 0)
			(layer "B.Fab")
			(effects
				(font
					(size 1.27 1.27)
				)
				(justify mirror)
			)
		)
		(duplicate_pad_numbers_are_jumpers no)
		(fp_poly
			(pts
				(xy -0.3048 -0.1016) (xy -0.3048 0.9906) (xy 0.3048 0.9906) (xy 0.3048 -0.1016)
			)
			(stroke
				(width 0)
				(type default)
			)
			(fill no)
			(layer "B.CrtYd")
		)
		(fp_line
			(start -0.3048 -0.1016)
			(end 0.3048 -0.1016)
			(stroke
				(width 0.1)
				(type default)
			)
			(layer "B.Fab")
		)
		(fp_line
			(start -0.3048 0.9906)
			(end -0.3048 -0.1016)
			(stroke
				(width 0.1)
				(type default)
			)
			(layer "B.Fab")
		)
		(fp_line
			(start 0.3048 -0.1016)
			(end 0.3048 0.9906)
			(stroke
				(width 0.1)
				(type default)
			)
			(layer "B.Fab")
		)
		(fp_line
			(start 0.3048 0.9906)
			(end -0.3048 0.9906)
			(stroke
				(width 0.1)
				(type default)
			)
			(layer "B.Fab")
		)
		(pad "1" smd rect
			(at 0 0 180)
			(size 0.508 0.508)
			(layers "B.Cu" "B.Mask" "B.Paste")
			(net "P3E_CPU0_PE3_OCP_TXN<2>")
		)
		(pad "2" smd rect
			(at 0 0.889 180)
			(size 0.508 0.508)
			(layers "B.Cu" "B.Mask" "B.Paste")
			(net "P3E_OCP_CPU0_PE3_C_TXN<2>")
		)
		(zone
			(layer "B.Cu")
			(hatch none 0.5)
			(connect_pads
				(clearance 0)
			)
			(min_thickness 0.25)
			(keepout
				(tracks allowed)
				(vias not_allowed)
				(pads allowed)
				(copperpour not_allowed)
				(footprints allowed)
			)
			(placement
				(enabled no)
				(sheetname "")
			)
			(fill
				(thermal_gap 0.5)
				(thermal_bridge_width 0.5)
				(island_removal_mode 0)
			)
			(polygon
				(pts
					(xy 457.7588 -52.229258) (xy 457.2508 -52.229258) (xy 457.2508 -51.848258) (xy 457.7588 -51.848258)
				)
			)
		)
	)
)
